(kicad_pcb
	(version 20221018)
	(generator pcbnew)
	(general
    (thickness 1.518)
  )
	(paper "A4")
	(title_block
    (title "Kria K26 Devboard")
    (date "2024-03-26")
    (rev "1.2.5")
    (comment 1 "www.antmicro.com")
    (comment 2 "Antmicro Ltd.")
		(comment 9 "footprints 105-109 of 660")
	)
	(layers
    (0 "F.Cu" mixed)
    (1 "In1.Cu" power)
    (2 "In2.Cu" mixed)
    (3 "In3.Cu" power)
    (4 "In4.Cu" mixed)
    (5 "In5.Cu" power)
    (6 "In6.Cu" mixed)
    (31 "B.Cu" power)
    (32 "B.Adhes" user "B.Adhesive")
    (33 "F.Adhes" user "F.Adhesive")
    (34 "B.Paste" user)
    (35 "F.Paste" user)
    (36 "B.SilkS" user "B.Silkscreen")
    (37 "F.SilkS" user "F.Silkscreen")
    (38 "B.Mask" user)
    (39 "F.Mask" user)
    (40 "Dwgs.User" user "User.Drawings")
    (41 "Cmts.User" user "User.Comments")
    (42 "Eco1.User" user "User.Eco1")
    (43 "Eco2.User" user "User.Eco2")
    (44 "Edge.Cuts" user)
    (45 "Margin" user)
    (46 "B.CrtYd" user "B.Courtyard")
    (47 "F.CrtYd" user "F.Courtyard")
    (48 "B.Fab" user)
    (49 "F.Fab" user)
  )
	(footprint "kria-k26-devboard-footprints:DFN-8-1EP_3x2mm_P0.5mm_EP1.36x1.46mm" (layer "F.Cu")
    (at 140.50176 112.579792 180)
    (property "Author" "Antmicro")
    (property "License" "Apache-2.0")
    (property "MPN" "93LC66BT-I/MC")
    (property "Manufacturer" "Microchip Technology")
    (property "Sheetfile" "debug.kicad_sch")
    (property "Sheetname" "Debug and JTAG")
    (property "ki_description" "EEPROM, 4 Kbit, 256 x 16bit, Serial Microwire, 2 MHz, DFN-EP-8")
    (property "ki_keywords" "SMT, MEMORY, IC, EEPROM")
    (attr smd)
    (fp_text reference "U39" (at 1.96176 1.139792 90) (layer "F.SilkS")
        (effects (font (size 0.7 0.7) (thickness 0.15)) (justify right bottom))
    )
    (fp_text value "93LC66BT_DFN" (at 0 2.2) (layer "F.Fab")
        (effects (font (size 0.7 0.7) (thickness 0.15)) (justify right bottom))
    )
    (fp_text user "${REFERENCE}" (at -2.27 4.052) (layer "F.Fab") hide
        (effects (font (size 0.7 0.7) (thickness 0.15)) (justify right bottom))
    )
    (fp_text user "License: Apache-2.0" (at -2.27 6.453) (layer "F.Fab") hide
        (effects (font (size 0.7 0.7) (thickness 0.15)) (justify right bottom))
    )
    (fp_text user "Author: Antmicro" (at -2.27 5.253) (layer "F.Fab") hide
        (effects (font (size 0.7 0.7) (thickness 0.15)) (justify right bottom))
    )
    (fp_line (start -1.501 1.111) (end 1.518 1.111)
      (stroke (width 0.15) (type solid)) (layer "F.SilkS"))
    (fp_line (start 1.498 -1.12) (end -1.511 -1.12)
      (stroke (width 0.15) (type solid)) (layer "F.SilkS"))
    (fp_circle (center -1.751 -1.05) (end -1.7 -1.05)
      (stroke (width 0.15) (type solid)) (fill solid) (layer "F.SilkS"))
    (fp_line (start -1.901 -1.262) (end 1.889 -1.262)
      (stroke (width 0.05) (type solid)) (layer "F.CrtYd"))
    (fp_line (start -1.901 1.228) (end -1.901 -1.262)
      (stroke (width 0.05) (type solid)) (layer "F.CrtYd"))
    (fp_line (start 1.889 -1.262) (end 1.889 1.228)
      (stroke (width 0.05) (type solid)) (layer "F.CrtYd"))
    (fp_line (start 1.889 1.228) (end -1.901 1.228)
      (stroke (width 0.05) (type solid)) (layer "F.CrtYd"))
    (fp_line (start -1.501 0.99) (end -1.501 -0.989)
      (stroke (width 0.15) (type solid)) (layer "F.Fab"))
    (fp_line (start 1.498 -0.999) (end -1.491 -0.999)
      (stroke (width 0.15) (type solid)) (layer "F.Fab"))
    (fp_line (start 1.498 -0.999) (end 1.498 0.99)
      (stroke (width 0.15) (type solid)) (layer "F.Fab"))
    (fp_line (start 1.498 0.999) (end -1.501 0.999)
      (stroke (width 0.15) (type solid)) (layer "F.Fab"))
    (pad "1" smd rect (at -1.451 -0.749 90) (size 0.3 0.7) (layers "F.Cu" "F.Paste" "F.Mask")
      (net 232 "/Debug and JTAG/EECS") (pinfunction "CS") (pintype "input"))
    (pad "2" smd rect (at -1.451 -0.25 90) (size 0.3 0.7) (layers "F.Cu" "F.Paste" "F.Mask")
      (net 231 "/Debug and JTAG/EECLK") (pinfunction "SCLK") (pintype "input"))
    (pad "3" smd rect (at -1.451 0.249 90) (size 0.3 0.7) (layers "F.Cu" "F.Paste" "F.Mask")
      (net 230 "/Debug and JTAG/EEDATA") (pinfunction "DI") (pintype "input"))
    (pad "4" smd rect (at -1.451 0.75 90) (size 0.3 0.7) (layers "F.Cu" "F.Paste" "F.Mask")
      (net 682 "Net-(U39-DO)") (pinfunction "DO") (pintype "tri_state"))
    (pad "5" smd rect (at 1.448 0.75 90) (size 0.3 0.7) (layers "F.Cu" "F.Paste" "F.Mask")
      (net 1 "GND") (pinfunction "GND") (pintype "power_in"))
    (pad "6" smd rect (at 1.448 0.249 90) (size 0.3 0.7) (layers "F.Cu" "F.Paste" "F.Mask")
      (net 736 "unconnected-(U39-ORG-Pad6)") (pinfunction "ORG") (pintype "input+no_connect"))
    (pad "7" smd rect (at 1.448 -0.25 90) (size 0.3 0.7) (layers "F.Cu" "F.Paste" "F.Mask")
      (net 737 "unconnected-(U39-NC-Pad7)") (pinfunction "NC") (pintype "no_connect"))
    (pad "8" smd rect (at 1.448 -0.749 90) (size 0.3 0.7) (layers "F.Cu" "F.Paste" "F.Mask")
      (net 138 "/Debug and JTAG/USB_3V3") (pinfunction "VCC") (pintype "power_in"))
    (pad "9" smd rect (at 0 0 90) (size 1.5 1.7) (layers "F.Cu" "F.Paste" "F.Mask")
      (net 1 "GND") (pinfunction "EP") (pintype "passive") (solder_paste_margin_ratio -0.1))
  )
	(footprint "kria-k26-devboard-footprints:R_0402_1005Metric" (layer "F.Cu")
    (at 141.578409 128.118647 180)
    (descr "Resistor SMD 0402")
    (tags "resistor SMD 0402")
    (property "Author" "Antmicro")
    (property "License" "Apache-2.0")
    (property "MPN" "CR0402-FX-1002GLF")
    (property "Manufacturer" "Bourns")
    (property "Sheetfile" "debug.kicad_sch")
    (property "Sheetname" "Debug and JTAG")
    (property "Tolerance" "1%")
    (property "Val" "10k")
    (property "ki_description" "10k resistor in 0402 package with 1% tolerance")
    (attr smd)
    (fp_text reference "R113" (at -0.891591 -0.391353 180) (layer "F.SilkS")
        (effects (font (size 0.7 0.7) (thickness 0.15)) (justify left bottom))
    )
    (fp_text value "R_10k_0402" (at 0 1.4 180) (layer "F.Fab") hide
        (effects (font (size 0.7 0.7) (thickness 0.15)) (justify left bottom))
    )
    (fp_text user "License: Apache-2.0" (at -0.95 5.169 180) (layer "F.Fab") hide
        (effects (font (size 0.7 0.7) (thickness 0.15)) (justify left bottom))
    )
    (fp_text user "Author: Antmicro" (at -0.95 4.169 180) (layer "F.Fab") hide
        (effects (font (size 0.7 0.7) (thickness 0.15)) (justify left bottom))
    )
    (fp_text user "${REFERENCE}" (at -0.95 3.168 180) (layer "F.Fab") hide
        (effects (font (size 0.7 0.7) (thickness 0.15)) (justify left bottom))
    )
    (fp_rect (start -0.93 -0.47) (end 0.93 0.47)
      (stroke (width 0.05) (type solid)) (fill none) (layer "F.CrtYd"))
    (fp_rect (start -0.5 -0.25) (end 0.5 0.25)
      (stroke (width 0.15) (type solid)) (fill none) (layer "F.Fab"))
    (pad "1" smd roundrect (at -0.485 0 180) (size 0.59 0.64) (layers "F.Cu" "F.Paste" "F.Mask") (roundrect_rratio 0.25)
      (net 138 "/Debug and JTAG/USB_3V3") (pintype "passive"))
    (pad "2" smd roundrect (at 0.485 0 180) (size 0.59 0.64) (layers "F.Cu" "F.Paste" "F.Mask") (roundrect_rratio 0.25)
      (net 683 "Net-(U44-B_{1})") (pintype "passive"))
  )
	(footprint "kria-k26-devboard-footprints:R_0402_1005Metric" (layer "F.Cu")
    (at 139.109974 128.122183)
    (descr "Resistor SMD 0402")
    (tags "resistor SMD 0402")
    (property "Author" "Antmicro")
    (property "License" "Apache-2.0")
    (property "MPN" "CR0402-FX-1002GLF")
    (property "Manufacturer" "Bourns")
    (property "Sheetfile" "debug.kicad_sch")
    (property "Sheetname" "Debug and JTAG")
    (property "Tolerance" "1%")
    (property "Val" "10k")
    (property "ki_description" "10k resistor in 0402 package with 1% tolerance")
    (attr smd)
    (fp_text reference "R114" (at -0.409974 -0.222183 90) (layer "F.SilkS")
        (effects (font (size 0.7 0.7) (thickness 0.15)) (justify left bottom))
    )
    (fp_text value "R_10k_0402" (at 0 1.4) (layer "F.Fab") hide
        (effects (font (size 0.7 0.7) (thickness 0.15)) (justify left bottom))
    )
    (fp_text user "${REFERENCE}" (at -0.95 3.168) (layer "F.Fab") hide
        (effects (font (size 0.7 0.7) (thickness 0.15)) (justify left bottom))
    )
    (fp_text user "Author: Antmicro" (at -0.95 4.169) (layer "F.Fab") hide
        (effects (font (size 0.7 0.7) (thickness 0.15)) (justify left bottom))
    )
    (fp_text user "License: Apache-2.0" (at -0.95 5.169) (layer "F.Fab") hide
        (effects (font (size 0.7 0.7) (thickness 0.15)) (justify left bottom))
    )
    (fp_rect (start -0.93 -0.47) (end 0.93 0.47)
      (stroke (width 0.05) (type solid)) (fill none) (layer "F.CrtYd"))
    (fp_rect (start -0.5 -0.25) (end 0.5 0.25)
      (stroke (width 0.15) (type solid)) (fill none) (layer "F.Fab"))
    (pad "1" smd roundrect (at -0.485 0) (size 0.59 0.64) (layers "F.Cu" "F.Paste" "F.Mask") (roundrect_rratio 0.25)
      (net 138 "/Debug and JTAG/USB_3V3") (pintype "passive"))
    (pad "2" smd roundrect (at 0.485 0) (size 0.59 0.64) (layers "F.Cu" "F.Paste" "F.Mask") (roundrect_rratio 0.25)
      (net 684 "Net-(U44-B_{2})") (pintype "passive"))
  )
	(footprint "kria-k26-devboard-footprints:UQFN-10_1.4x1.8x0.5mm_P0.4mm" (layer "F.Cu")
    (at 140.371787 126.024767)
    (property "Author" "Antmicro")
    (property "License" "Apache-2.0")
    (property "MPN" "SN74AVC2T245RSWR")
    (property "Manufacturer" "Texas Instruments")
    (property "Sheetfile" "debug.kicad_sch")
    (property "Sheetname" "Debug and JTAG")
    (property "ki_description" "Transceiver Non Inverting, AVC Family, 2 Input, 12 mA, 2.4 ns, 1.2 V to 3.6 V, LFCSP-10")
    (property "ki_keywords" "SMT, LOGIC, IC, LEVEL-SHIFTER, VOLTAGE")
    (attr smd)
    (fp_text reference "U44" (at -0.531787 -1.584767) (layer "F.SilkS")
        (effects (font (size 0.7 0.7) (thickness 0.15)) (justify left bottom))
    )
    (fp_text value "SN74AVC2T245_UQFN" (at 0 2.4) (layer "F.Fab") hide
        (effects (font (size 0.7 0.7) (thickness 0.15)) (justify left bottom))
    )
    (fp_text user "Author: Antmicro" (at -0.657 5.7) (layer "F.Fab") hide
        (effects (font (size 0.7 0.7) (thickness 0.15)) (justify left bottom))
    )
    (fp_text user "${REFERENCE}" (at -0.657 4.498) (layer "F.Fab") hide
        (effects (font (size 0.7 0.7) (thickness 0.15)) (justify left bottom))
    )
    (fp_text user "License: Apache-2.0" (at -0.657 6.9) (layer "F.Fab") hide
        (effects (font (size 0.7 0.7) (thickness 0.15)) (justify left bottom))
    )
    (fp_line (start -0.7305 -0.552) (end -1.2005 -0.552)
      (stroke (width 0.15) (type solid)) (layer "F.SilkS"))
    (fp_line (start -0.7305 -0.552) (end -0.7305 -0.93)
      (stroke (width 0.15) (type solid)) (layer "F.SilkS"))
    (fp_circle (center -1.0515 -1.151) (end -0.9805 -1.151)
      (stroke (width 0.15) (type solid)) (fill none) (layer "F.SilkS"))
    (fp_rect (start -1.3 -1.5) (end 1.3 1.5)
      (stroke (width 0.05) (type solid)) (fill none) (layer "F.CrtYd"))
    (fp_line (start -0.7 -0.4) (end -0.175 -0.925)
      (stroke (width 0.15) (type solid)) (layer "F.Fab"))
    (fp_line (start -0.7 0.93) (end -0.7 -0.4)
      (stroke (width 0.15) (type solid)) (layer "F.Fab"))
    (fp_line (start -0.175 -0.925) (end 0.7295 -0.925)
      (stroke (width 0.15) (type solid)) (layer "F.Fab"))
    (fp_line (start 0.725 0.93) (end -0.7 0.93)
      (stroke (width 0.15) (type solid)) (layer "F.Fab"))
    (fp_line (start 0.7295 -0.925) (end 0.725 0.93)
      (stroke (width 0.15) (type solid)) (layer "F.Fab"))
    (pad "1" smd roundrect (at -0.6445 -0.2) (size 0.81 0.22) (layers "F.Cu" "F.Paste" "F.Mask") (roundrect_rratio 0.25)
      (net 138 "/Debug and JTAG/USB_3V3") (pinfunction "DIR_{2}") (pintype "input"))
    (pad "2" smd roundrect (at -0.6445 0.2) (size 0.81 0.22) (layers "F.Cu" "F.Paste" "F.Mask") (roundrect_rratio 0.25)
      (net 164 "/Debug and JTAG/~{FTDI_PWREN}") (pinfunction "~{OE}") (pintype "input"))
    (pad "3" smd roundrect (at -0.4015 0.844 270) (size 0.81 0.22) (layers "F.Cu" "F.Paste" "F.Mask") (roundrect_rratio 0.25)
      (net 1 "GND") (pinfunction "GND") (pintype "power_in"))
    (pad "4" smd roundrect (at 0.0005 0.844 270) (size 0.81 0.22) (layers "F.Cu" "F.Paste" "F.Mask") (roundrect_rratio 0.25)
      (net 684 "Net-(U44-B_{2})") (pinfunction "B_{2}") (pintype "bidirectional"))
    (pad "5" smd roundrect (at 0.3995 0.844 270) (size 0.81 0.22) (layers "F.Cu" "F.Paste" "F.Mask") (roundrect_rratio 0.25)
      (net 683 "Net-(U44-B_{1})") (pinfunction "B_{1}") (pintype "bidirectional"))
    (pad "6" smd roundrect (at 0.6455 0.2) (size 0.81 0.22) (layers "F.Cu" "F.Paste" "F.Mask") (roundrect_rratio 0.25)
      (net 138 "/Debug and JTAG/USB_3V3") (pinfunction "V_{CCB}") (pintype "power_in"))
    (pad "7" smd roundrect (at 0.6455 -0.2) (size 0.81 0.22) (layers "F.Cu" "F.Paste" "F.Mask") (roundrect_rratio 0.25)
      (net 138 "/Debug and JTAG/USB_3V3") (pinfunction "V_{CCA}") (pintype "power_in"))
    (pad "8" smd roundrect (at 0.3995 -0.847 270) (size 0.81 0.22) (layers "F.Cu" "F.Paste" "F.Mask") (roundrect_rratio 0.25)
      (net 167 "/Debug and JTAG/~{FTDI_PS_SRST}") (pinfunction "A_{1}") (pintype "bidirectional"))
    (pad "9" smd roundrect (at 0.0005 -0.847 270) (size 0.81 0.22) (layers "F.Cu" "F.Paste" "F.Mask") (roundrect_rratio 0.25)
      (net 168 "/Debug and JTAG/~{FTDI_PS_POR}") (pinfunction "A_{2}") (pintype "bidirectional"))
    (pad "10" smd roundrect (at -0.4015 -0.847 270) (size 0.81 0.22) (layers "F.Cu" "F.Paste" "F.Mask") (roundrect_rratio 0.25)
      (net 138 "/Debug and JTAG/USB_3V3") (pinfunction "DIR_{1}") (pintype "input"))
  )
	(footprint "kria-k26-devboard-footprints:SOT-363" (layer "F.Cu")
    (at 140.401076 130.15 -90)
    (property "Author" "Antmicro")
    (property "License" "Apache-2.0")
    (property "MPN" "NC7WZ07P6X")
    (property "Manufacturer" "ON Semiconductor")
    (property "Sheetfile" "debug.kicad_sch")
    (property "Sheetname" "Debug and JTAG")
    (property "ki_description" "Buffer, 1.65 V to 5.5 V, SC-70-6")
    (property "ki_keywords" "SMT, DRIVER, IC, LOGIC")
    (attr smd)
    (fp_text reference "U46" (at 2.19 -1.088924 180) (layer "F.SilkS")
        (effects (font (size 0.7 0.7) (thickness 0.15)) (justify right bottom))
    )
    (fp_text value "NC7WZ07_SC" (at 0 2.2 90) (layer "F.Fab") hide
        (effects (font (size 0.7 0.7) (thickness 0.15)) (justify right bottom))
    )
    (fp_text user "License: Apache-2.0" (at -1.3 5.2 90) (layer "F.Fab") hide
        (effects (font (size 0.7 0.7) (thickness 0.15)) (justify right bottom))
    )
    (fp_text user "Author: Antmicro" (at -1.3 6.4 90) (layer "F.Fab") hide
        (effects (font (size 0.7 0.7) (thickness 0.15)) (justify right bottom))
    )
    (fp_text user "${REFERENCE}" (at -1.3 4 90) (layer "F.Fab") hide
        (effects (font (size 0.7 0.7) (thickness 0.15)) (justify right bottom))
    )
    (fp_line (start -0.8 1.146) (end -0.8 1.223)
      (stroke (width 0.15) (type solid)) (layer "F.SilkS"))
    (fp_line (start -0.8 1.223) (end 0.803 1.223)
      (stroke (width 0.15) (type solid)) (layer "F.SilkS"))
    (fp_line (start -0.72 -1.153) (end -0.72 -1.228)
      (stroke (width 0.15) (type solid)) (layer "F.SilkS"))
    (fp_line (start 0.803 -1.228) (end -0.72 -1.228)
      (stroke (width 0.15) (type solid)) (layer "F.SilkS"))
    (fp_line (start 0.803 -1.153) (end 0.803 -1.228)
      (stroke (width 0.15) (type solid)) (layer "F.SilkS"))
    (fp_line (start 0.803 1.146) (end 0.803 1.223)
      (stroke (width 0.15) (type solid)) (layer "F.SilkS"))
    (fp_circle (center -0.978102 -1.2) (end -0.928102 -1.2)
      (stroke (width 0.15) (type solid)) (fill solid) (layer "F.SilkS"))
    (fp_rect (start 1.3 -1.3) (end -1.3 1.3)
      (stroke (width 0.05) (type solid)) (fill none) (layer "F.CrtYd"))
    (fp_line (start -0.1 -1.1) (end -0.68 -0.52)
      (stroke (width 0.15) (type solid)) (layer "F.Fab"))
    (fp_rect (start 0.68 1.1) (end -0.68 -1.1)
      (stroke (width 0.15) (type solid)) (fill none) (layer "F.Fab"))
    (pad "1" smd custom (at -0.948 -0.752 180) (size 0.6 0.6) (layers "F.Cu" "F.Paste" "F.Mask")
      (net 683 "Net-(U44-B_{1})") (pintype "input") (zone_connect 0)
      (options (clearance outline) (anchor rect))
      (primitives
      ))
    (pad "2" smd rect (at -0.948 -0.002 180) (size 0.4 0.6) (layers "F.Cu" "F.Paste" "F.Mask")
      (net 1 "GND") (pinfunction "GND") (pintype "power_in"))
    (pad "3" smd custom (at -0.948 0.745 180) (size 0.6 0.6) (layers "F.Cu" "F.Paste" "F.Mask")
      (net 684 "Net-(U44-B_{2})") (pintype "input") (zone_connect 0)
      (options (clearance outline) (anchor rect))
      (primitives
      ))
    (pad "4" smd custom (at 0.951 0.745 180) (size 0.6 0.6) (layers "F.Cu" "F.Paste" "F.Mask")
      (net 151 "/Debug and JTAG/~{PS_POR}") (pintype "output") (zone_connect 0)
      (options (clearance outline) (anchor rect))
      (primitives
      ))
    (pad "5" smd rect (at 0.951 -0.002 180) (size 0.4 0.6) (layers "F.Cu" "F.Paste" "F.Mask")
      (net 138 "/Debug and JTAG/USB_3V3") (pinfunction "VCC") (pintype "power_in"))
    (pad "6" smd custom (at 0.951 -0.752 180) (size 0.6 0.6) (layers "F.Cu" "F.Paste" "F.Mask")
      (net 140 "/Debug and JTAG/~{PS_SRST_C2M}") (pintype "output") (zone_connect 0)
      (options (clearance outline) (anchor rect))
      (primitives
      ))
  )
)
